# S9S_MB_2U (Grand Teton) — schematic netlist excerpt (pin names and nets, part order shuffled) for the footprints in the layout excerpt that follows; sources: Cadence DE-HDL packaged netlist, KiCad conversion of 03242023_DA0F0TMBIJ0_F0T_Motherboard_J_brd_V01_OCP.brd

C2265  Q_CAP  1000PF 50V 5% EMPTY  pkg 0402  page 146 : A = PRSNT_CABLE_GPU_B3_ISO_N ; B = GND
R3498  Q_RES  54.9K 1% CHIP  pkg 0402LF  page 147 : A = P3V3_AUX ; B = GPU_FPGA_THERM_OVERT_N
C1537  Q_CAP_DIFFBUS  DIFF BUS_0.22UF 6.3V 20% X6S  pkg C0201  page 177 : \1\ = P5E_CPU1_PE3_TX_C_DP<5> ; \2\ = P5E_CPU1_PE3_TX_DP<5>

(kicad_pcb
	(version 20260206)
	(generator "pcbnew")
	(generator_version "10.0")
	(general
		(thickness 1.6)
		(legacy_teardrops no)
	)
	(paper "A4")
	(title_block
		(title "03242023_DA0F0TMBIJ0_F0T_Motherboard_J_brd_V01_OCP.brd")
		(comment 1 "Grand Teton / footprints 2021-2023 of 6105")
	)
	(layers
		(0 "F.Cu" signal "TOP")
		(4 "In1.Cu" signal "GND")
		(6 "In2.Cu" signal "IN1")
		(8 "In3.Cu" signal "GND1")
		(10 "In4.Cu" signal "IN2")
		(12 "In5.Cu" signal "GND2")
		(14 "In6.Cu" signal "IN3")
		(16 "In7.Cu" signal "GND3")
		(18 "In8.Cu" signal "VCC")
		(20 "In9.Cu" signal "VCC1")
		(22 "In10.Cu" signal "GND4")
		(24 "In11.Cu" signal "IN4")
		(26 "In12.Cu" signal "GND5")
		(28 "In13.Cu" signal "IN5")
		(30 "In14.Cu" signal "GND6")
		(32 "In15.Cu" signal "IN6")
		(34 "In16.Cu" signal "GND7")
		(2 "B.Cu" signal "BOTTOM")
		(9 "F.Adhes" user "F.Adhesive")
		(11 "B.Adhes" user "B.Adhesive")
		(13 "F.Paste" user "Package Geometry/Pastemask Top")
		(15 "B.Paste" user "Package Geometry/Pastemask Bottom")
		(5 "F.SilkS" user "Ref Des/Silkscreen Top")
		(7 "B.SilkS" user "Ref Des/Silkscreen Bottom")
		(1 "F.Mask" user "Board Geometry/Soldermask Top")
		(3 "B.Mask" user "Board Geometry/Soldermask Bottom")
		(17 "Dwgs.User" user "User.Drawings")
		(19 "Cmts.User" user "User.Comments")
		(21 "Eco1.User" user "User.Eco1")
		(23 "Eco2.User" user "User.Eco2")
		(25 "Edge.Cuts" user "Board Geometry/Outline")
		(27 "Margin" user)
		(31 "F.CrtYd" user "Package Geometry/Place Bound Top")
		(29 "B.CrtYd" user "Package Geometry/Place Bound Bottom")
		(35 "F.Fab" user "Ref Des/Assembly Top")
		(33 "B.Fab" user "Ref Des/Assembly Bottom")
	)
	(footprint ""
		(layer "F.Cu")
		(at 153.022554 -408.517344 -90)
		(property "Reference" "C1537"
			(at 0 0 270)
			(layer "F.SilkS")
			(hide yes)
			(effects
				(font
					(size 1.27 1.27)
				)
			)
		)
		(property "Value" ""
			(at 0 0 270)
			(layer "F.Fab")
			(effects
				(font
					(size 1.27 1.27)
				)
			)
		)
		(duplicate_pad_numbers_are_jumpers no)
		(fp_line
			(start -0.299974 0.150114)
			(end -0.299974 -0.150114)
			(stroke
				(width 0.1)
				(type default)
			)
			(layer "F.Fab")
		)
		(fp_line
			(start 0.299974 0.150114)
			(end -0.299974 0.150114)
			(stroke
				(width 0.1)
				(type default)
			)
			(layer "F.Fab")
		)
		(fp_line
			(start -0.299974 -0.150114)
			(end 0.299974 -0.150114)
			(stroke
				(width 0.1)
				(type default)
			)
			(layer "F.Fab")
		)
		(fp_line
			(start 0.299974 -0.150114)
			(end 0.299974 0.150114)
			(stroke
				(width 0.1)
				(type default)
			)
			(layer "F.Fab")
		)
		(pad "1" smd rect
			(at -0.2667 0 270)
			(size 0.3048 0.381)
			(layers "F.Cu" "F.Mask" "F.Paste")
			(net "P5E_CPU1_PE3_TX_C_DP<5>")
		)
		(pad "2" smd rect
			(at 0.2667 0 270)
			(size 0.3048 0.381)
			(layers "F.Cu" "F.Mask" "F.Paste")
			(net "P5E_CPU1_PE3_TX_DP<5>")
		)
	)
	(footprint ""
		(layer "F.Cu")
		(at 24.069802 -406.874218)
		(property "Reference" "R3498"
			(at 0 0 0)
			(layer "F.SilkS")
			(hide yes)
			(effects
				(font
					(size 1.27 1.27)
				)
			)
		)
		(property "Value" ""
			(at 0 0 0)
			(layer "F.Fab")
			(effects
				(font
					(size 1.27 1.27)
				)
			)
		)
		(duplicate_pad_numbers_are_jumpers no)
		(fp_line
			(start -0.7874 -0.4064)
			(end 0.7874 -0.4064)
			(stroke
				(width 0.1524)
				(type default)
			)
			(layer "F.SilkS")
		)
		(fp_line
			(start -0.7874 0.4064)
			(end -0.7874 -0.4064)
			(stroke
				(width 0.1524)
				(type default)
			)
			(layer "F.SilkS")
		)
		(fp_line
			(start 0.7874 -0.4064)
			(end 0.7874 0.4064)
			(stroke
				(width 0.1524)
				(type default)
			)
			(layer "F.SilkS")
		)
		(fp_line
			(start 0.7874 0.4064)
			(end -0.7874 0.4064)
			(stroke
				(width 0.1524)
				(type default)
			)
			(layer "F.SilkS")
		)
		(fp_line
			(start -0.67945 -0.305054)
			(end -0.12065 -0.305054)
			(stroke
				(width 0.1)
				(type default)
			)
			(layer "F.Fab")
		)
		(fp_line
			(start -0.67945 0.3048)
			(end -0.67945 -0.305054)
			(stroke
				(width 0.1)
				(type default)
			)
			(layer "F.Fab")
		)
		(fp_line
			(start -0.12065 -0.305054)
			(end -0.12065 -0.2794)
			(stroke
				(width 0.1)
				(type default)
			)
			(layer "F.Fab")
		)
		(fp_line
			(start -0.12065 -0.2794)
			(end 0.12065 -0.2794)
			(stroke
				(width 0.1)
				(type default)
			)
			(layer "F.Fab")
		)
		(fp_line
			(start -0.12065 0.2794)
			(end -0.12065 0.3048)
			(stroke
				(width 0.1)
				(type default)
			)
			(layer "F.Fab")
		)
		(fp_line
			(start -0.12065 0.3048)
			(end -0.67945 0.3048)
			(stroke
				(width 0.1)
				(type default)
			)
			(layer "F.Fab")
		)
		(fp_line
			(start 0.120396 0.2794)
			(end -0.12065 0.2794)
			(stroke
				(width 0.1)
				(type default)
			)
			(layer "F.Fab")
		)
		(fp_line
			(start 0.120396 0.3048)
			(end 0.120396 0.2794)
			(stroke
				(width 0.1)
				(type default)
			)
			(layer "F.Fab")
		)
		(fp_line
			(start 0.12065 -0.3048)
			(end 0.67945 -0.3048)
			(stroke
				(width 0.1)
				(type default)
			)
			(layer "F.Fab")
		)
		(fp_line
			(start 0.12065 -0.2794)
			(end 0.12065 -0.3048)
			(stroke
				(width 0.1)
				(type default)
			)
			(layer "F.Fab")
		)
		(fp_line
			(start 0.67945 -0.3048)
			(end 0.67945 0.3048)
			(stroke
				(width 0.1)
				(type default)
			)
			(layer "F.Fab")
		)
		(fp_line
			(start 0.67945 0.3048)
			(end 0.120396 0.3048)
			(stroke
				(width 0.1)
				(type default)
			)
			(layer "F.Fab")
		)
		(pad "1" smd circle
			(at -0.40005 0)
			(size 0 0)
			(layers "F.Cu" "F.Mask" "F.Paste")
			(net "P3V3_AUX")
		)
		(pad "2" smd circle
			(at 0.40005 0)
			(size 0 0)
			(layers "F.Cu" "F.Mask" "F.Paste")
			(net "GPU_FPGA_THERM_OVERT_N")
		)
	)
	(footprint ""
		(layer "F.Cu")
		(at 301.45482 -419.02761 -90)
		(property "Reference" "C2265"
			(at 0 0 270)
			(layer "F.SilkS")
			(hide yes)
			(effects
				(font
					(size 1.27 1.27)
				)
			)
		)
		(property "Value" ""
			(at 0 0 270)
			(layer "F.Fab")
			(effects
				(font
					(size 1.27 1.27)
				)
			)
		)
		(duplicate_pad_numbers_are_jumpers no)
		(fp_line
			(start -0.7874 0.4064)
			(end -0.7874 -0.4064)
			(stroke
				(width 0.1524)
				(type default)
			)
			(layer "F.SilkS")
		)
		(fp_line
			(start 0.7874 0.4064)
			(end -0.7874 0.4064)
			(stroke
				(width 0.1524)
				(type default)
			)
			(layer "F.SilkS")
		)
		(fp_line
			(start -0.7874 -0.4064)
			(end 0.7874 -0.4064)
			(stroke
				(width 0.1524)
				(type default)
			)
			(layer "F.SilkS")
		)
		(fp_line
			(start 0.7874 -0.4064)
			(end 0.7874 0.4064)
			(stroke
				(width 0.1524)
				(type default)
			)
			(layer "F.SilkS")
		)
		(fp_line
			(start -0.67945 0.3048)
			(end -0.67945 -0.305054)
			(stroke
				(width 0.1)
				(type default)
			)
			(layer "F.Fab")
		)
		(fp_line
			(start -0.12065 0.3048)
			(end -0.67945 0.3048)
			(stroke
				(width 0.1)
				(type default)
			)
			(layer "F.Fab")
		)
		(fp_line
			(start 0.120396 0.3048)
			(end 0.120396 0.2794)
			(stroke
				(width 0.1)
				(type default)
			)
			(layer "F.Fab")
		)
		(fp_line
			(start 0.67945 0.3048)
			(end 0.120396 0.3048)
			(stroke
				(width 0.1)
				(type default)
			)
			(layer "F.Fab")
		)
		(fp_line
			(start -0.12065 0.2794)
			(end -0.12065 0.3048)
			(stroke
				(width 0.1)
				(type default)
			)
			(layer "F.Fab")
		)
		(fp_line
			(start 0.120396 0.2794)
			(end -0.12065 0.2794)
			(stroke
				(width 0.1)
				(type default)
			)
			(layer "F.Fab")
		)
		(fp_line
			(start -0.12065 -0.2794)
			(end 0.12065 -0.2794)
			(stroke
				(width 0.1)
				(type default)
			)
			(layer "F.Fab")
		)
		(fp_line
			(start 0.12065 -0.2794)
			(end 0.12065 -0.3048)
			(stroke
				(width 0.1)
				(type default)
			)
			(layer "F.Fab")
		)
		(fp_line
			(start 0.12065 -0.3048)
			(end 0.67945 -0.3048)
			(stroke
				(width 0.1)
				(type default)
			)
			(layer "F.Fab")
		)
		(fp_line
			(start 0.67945 -0.3048)
			(end 0.67945 0.3048)
			(stroke
				(width 0.1)
				(type default)
			)
			(layer "F.Fab")
		)
		(fp_line
			(start -0.67945 -0.305054)
			(end -0.12065 -0.305054)
			(stroke
				(width 0.1)
				(type default)
			)
			(layer "F.Fab")
		)
		(fp_line
			(start -0.12065 -0.305054)
			(end -0.12065 -0.2794)
			(stroke
				(width 0.1)
				(type default)
			)
			(layer "F.Fab")
		)
		(pad "1" smd circle
			(at -0.40005 0 270)
			(size 0 0)
			(layers "F.Cu" "F.Mask" "F.Paste")
			(net "PRSNT_CABLE_GPU_B3_ISO_N")
		)
		(pad "2" smd circle
			(at 0.40005 0 270)
			(size 0 0)
			(layers "F.Cu" "F.Mask" "F.Paste")
			(net "GND")
		)
	)
)
